(kicad_pcb
	(version 20260206)
	(generator "pcbnew")
	(generator_version "10.0")
	(general
		(thickness 1.6)
		(legacy_teardrops no)
	)
	(paper "A4")
	(title_block
		(title "Wiwynn_Tioga_Pass_MB.brd")
		(comment 1 "Tioga Pass / footprints 3834-3841 of 4770")
	)
	(layers
		(0 "F.Cu" signal "TOP")
		(4 "In1.Cu" signal "L2GND")
		(6 "In2.Cu" signal "L3")
		(8 "In3.Cu" signal "L4GND")
		(10 "In4.Cu" signal "L5")
		(12 "In5.Cu" signal "L6GND")
		(14 "In6.Cu" signal "L7VCC")
		(16 "In7.Cu" signal "L8VCC")
		(18 "In8.Cu" signal "L9GND")
		(20 "In9.Cu" signal "L10")
		(22 "In10.Cu" signal "L11GND")
		(24 "In11.Cu" signal "L12")
		(26 "In12.Cu" signal "L13GND")
		(2 "B.Cu" signal "BOTTOM")
		(9 "F.Adhes" user "F.Adhesive")
		(11 "B.Adhes" user "B.Adhesive")
		(13 "F.Paste" user "Package Geometry/Pastemask Top")
		(15 "B.Paste" user "Package Geometry/Pastemask Bottom")
		(5 "F.SilkS" user "Ref Des/Silkscreen Top")
		(7 "B.SilkS" user "Ref Des/Silkscreen Bottom")
		(1 "F.Mask" user "Board Geometry/Soldermask Top")
		(3 "B.Mask" user "Board Geometry/Soldermask Bottom")
		(17 "Dwgs.User" user "User.Drawings")
		(19 "Cmts.User" user "User.Comments")
		(21 "Eco1.User" user "User.Eco1")
		(23 "Eco2.User" user "User.Eco2")
		(25 "Edge.Cuts" user "Board Geometry/Outline")
		(27 "Margin" user)
		(31 "F.CrtYd" user "Package Geometry/Place Bound Top")
		(29 "B.CrtYd" user "Package Geometry/Place Bound Bottom")
		(35 "F.Fab" user "Ref Des/Assembly Top")
		(33 "B.Fab" user "Ref Des/Assembly Bottom")
	)
	(footprint ""
		(layer "B.Cu")
		(at 394.589 -85.9155)
		(property "Reference" "R2U12"
			(at 0 0 0)
			(layer "B.SilkS")
			(hide yes)
			(effects
				(font
					(size 1.27 1.27)
				)
				(justify mirror)
			)
		)
		(property "Value" ""
			(at 0 0 0)
			(layer "B.Fab")
			(effects
				(font
					(size 1.27 1.27)
				)
				(justify mirror)
			)
		)
		(duplicate_pad_numbers_are_jumpers no)
		(fp_poly
			(pts
				(xy 0.2794 -0.1016) (xy -0.2794 -0.1016) (xy -0.2794 0.9906) (xy 0.2794 0.9906)
			)
			(stroke
				(width 0)
				(type default)
			)
			(fill no)
			(layer "B.CrtYd")
		)
		(fp_line
			(start -0.2794 -0.1016)
			(end 0.2794 -0.1016)
			(stroke
				(width 0.1)
				(type default)
			)
			(layer "B.Fab")
		)
		(fp_line
			(start -0.2794 0.9906)
			(end -0.2794 -0.1016)
			(stroke
				(width 0.1)
				(type default)
			)
			(layer "B.Fab")
		)
		(fp_line
			(start 0.2794 -0.1016)
			(end 0.2794 0.9906)
			(stroke
				(width 0.1)
				(type default)
			)
			(layer "B.Fab")
		)
		(fp_line
			(start 0.2794 0.9906)
			(end -0.2794 0.9906)
			(stroke
				(width 0.1)
				(type default)
			)
			(layer "B.Fab")
		)
		(pad "1" smd rect
			(at 0 0 180)
			(size 0.508 0.508)
			(layers "B.Cu" "B.Mask" "B.Paste")
			(net "SMB_LAN_STBY_LVC3_SDA")
		)
		(pad "2" smd rect
			(at 0 0.889 180)
			(size 0.508 0.508)
			(layers "B.Cu" "B.Mask" "B.Paste")
			(net "SMB_OCP_FRU_STBY_LVC3_SDA")
		)
		(zone
			(layer "B.Cu")
			(hatch none 0.5)
			(connect_pads
				(clearance 0)
			)
			(min_thickness 0.25)
			(keepout
				(tracks allowed)
				(vias not_allowed)
				(pads allowed)
				(copperpour not_allowed)
				(footprints allowed)
			)
			(placement
				(enabled no)
				(sheetname "")
			)
			(fill
				(thermal_gap 0.5)
				(thermal_bridge_width 0.5)
				(island_removal_mode 0)
			)
			(polygon
				(pts
					(xy 394.843 -85.6615) (xy 394.335 -85.6615) (xy 394.335 -85.2805) (xy 394.843 -85.2805)
				)
			)
		)
		(zone
			(layer "B.Cu")
			(hatch none 0.5)
			(connect_pads
				(clearance 0)
			)
			(min_thickness 0.25)
			(keepout
				(tracks not_allowed)
				(vias allowed)
				(pads allowed)
				(copperpour not_allowed)
				(footprints allowed)
			)
			(placement
				(enabled no)
				(sheetname "")
			)
			(fill
				(thermal_gap 0.5)
				(thermal_bridge_width 0.5)
				(island_removal_mode 0)
			)
			(polygon
				(pts
					(xy 394.843 -85.2805) (xy 394.335 -85.2805) (xy 394.335 -85.6615) (xy 394.843 -85.6615)
				)
			)
		)
	)
	(footprint ""
		(layer "B.Cu")
		(at 400.7485 -106.172 -90)
		(property "Reference" "C2N26"
			(at 0 0 90)
			(layer "B.SilkS")
			(hide yes)
			(effects
				(font
					(size 1.27 1.27)
				)
				(justify mirror)
			)
		)
		(property "Value" ""
			(at 0 0 90)
			(layer "B.Fab")
			(effects
				(font
					(size 1.27 1.27)
				)
				(justify mirror)
			)
		)
		(duplicate_pad_numbers_are_jumpers no)
		(fp_poly
			(pts
				(xy -0.3048 -0.1016) (xy -0.3048 0.9906) (xy 0.3048 0.9906) (xy 0.3048 -0.1016)
			)
			(stroke
				(width 0)
				(type default)
			)
			(fill no)
			(layer "B.CrtYd")
		)
		(fp_line
			(start -0.3048 0.9906)
			(end -0.3048 -0.1016)
			(stroke
				(width 0.1)
				(type default)
			)
			(layer "B.Fab")
		)
		(fp_line
			(start 0.3048 0.9906)
			(end -0.3048 0.9906)
			(stroke
				(width 0.1)
				(type default)
			)
			(layer "B.Fab")
		)
		(fp_line
			(start -0.3048 -0.1016)
			(end 0.3048 -0.1016)
			(stroke
				(width 0.1)
				(type default)
			)
			(layer "B.Fab")
		)
		(fp_line
			(start 0.3048 -0.1016)
			(end 0.3048 0.9906)
			(stroke
				(width 0.1)
				(type default)
			)
			(layer "B.Fab")
		)
		(pad "1" smd rect
			(at 0 0 90)
			(size 0.508 0.508)
			(layers "B.Cu" "B.Mask" "B.Paste")
			(net "P3V3_STBY")
		)
		(pad "2" smd rect
			(at 0 0.889 90)
			(size 0.508 0.508)
			(layers "B.Cu" "B.Mask" "B.Paste")
			(net "GND")
		)
		(zone
			(layer "B.Cu")
			(hatch none 0.5)
			(connect_pads
				(clearance 0)
			)
			(min_thickness 0.25)
			(keepout
				(tracks not_allowed)
				(vias allowed)
				(pads allowed)
				(copperpour not_allowed)
				(footprints allowed)
			)
			(placement
				(enabled no)
				(sheetname "")
			)
			(fill
				(thermal_gap 0.5)
				(thermal_bridge_width 0.5)
				(island_removal_mode 0)
			)
			(polygon
				(pts
					(xy 400.1135 -105.918) (xy 400.1135 -106.426) (xy 400.4945 -106.426) (xy 400.4945 -105.918)
				)
			)
		)
		(zone
			(layer "B.Cu")
			(hatch none 0.5)
			(connect_pads
				(clearance 0)
			)
			(min_thickness 0.25)
			(keepout
				(tracks allowed)
				(vias not_allowed)
				(pads allowed)
				(copperpour not_allowed)
				(footprints allowed)
			)
			(placement
				(enabled no)
				(sheetname "")
			)
			(fill
				(thermal_gap 0.5)
				(thermal_bridge_width 0.5)
				(island_removal_mode 0)
			)
			(polygon
				(pts
					(xy 400.4945 -105.918) (xy 400.4945 -106.426) (xy 400.1135 -106.426) (xy 400.1135 -105.918)
				)
			)
		)
	)
	(footprint ""
		(layer "B.Cu")
		(at 446.381632 -37.032692 90)
		(property "Reference" "R25W12"
			(at 0 0 90)
			(layer "B.SilkS")
			(hide yes)
			(effects
				(font
					(size 1.27 1.27)
				)
				(justify mirror)
			)
		)
		(property "Value" "*"
			(at -0.064008 -4.108196 90)
			(unlocked yes)
			(layer "B.Fab")
			(hide yes)
			(effects
				(font
					(size 1.27 1.016)
					(thickness 0.1524)
				)
				(justify mirror)
			)
		)
		(property "Device Type" "120R2F-GP_RCL_GP-120R2F-GP,64.A"
			(at -0.064008 -5.632196 90)
			(unlocked yes)
			(layer "B.Fab")
			(hide yes)
			(effects
				(font
					(size 1.27 1.016)
					(thickness 0.1524)
				)
				(justify mirror)
			)
		)
		(duplicate_pad_numbers_are_jumpers no)
		(fp_line
			(start 0.508 -0.9398)
			(end 0.508 0.9398)
			(stroke
				(width 0.1524)
				(type default)
			)
			(layer "B.SilkS")
		)
		(fp_line
			(start -0.508 -0.9398)
			(end 0.508 -0.9398)
			(stroke
				(width 0.1524)
				(type default)
			)
			(layer "B.SilkS")
		)
		(fp_rect
			(start 0.508 0.9398)
			(end -0.508 -0.9398)
			(stroke
				(width 0)
				(type default)
			)
			(fill no)
			(layer "B.CrtYd")
		)
		(fp_rect
			(start 0.508 0.9398)
			(end -0.508 -0.9398)
			(stroke
				(width 0)
				(type default)
			)
			(fill no)
			(layer "B.Fab")
		)
		(pad "1" smd custom
			(at 0 -0.4445 270)
			(size 0.1397 0.1397)
			(layers "B.Cu" "B.Mask" "B.Paste")
			(net "GND")
			(options
				(clearance outline)
				(anchor circle)
			)
			(primitives
				(gr_poly
					(pts
						(arc
							(start -0.1778 0.2794)
							(mid -0.249642 0.249642)
							(end -0.2794 0.1778)
						)
						(arc
							(start -0.2794 -0.1778)
							(mid -0.249642 -0.249642)
							(end -0.1778 -0.2794)
						)
						(arc
							(start 0.1778 -0.2794)
							(mid 0.249642 -0.249642)
							(end 0.2794 -0.1778)
						)
						(arc
							(start 0.2794 0.1778)
							(mid 0.249642 0.249642)
							(end 0.1778 0.2794)
						)
					)
					(width 0)
					(fill yes)
				)
			)
		)
		(pad "2" smd custom
			(at 0 0.4445 270)
			(size 0.1397 0.1397)
			(layers "B.Cu" "B.Mask" "B.Paste")
			(net "BMC_M_A0")
			(options
				(clearance outline)
				(anchor circle)
			)
			(primitives
				(gr_poly
					(pts
						(arc
							(start -0.1778 0.2794)
							(mid -0.249642 0.249642)
							(end -0.2794 0.1778)
						)
						(arc
							(start -0.2794 -0.1778)
							(mid -0.249642 -0.249642)
							(end -0.1778 -0.2794)
						)
						(arc
							(start 0.1778 -0.2794)
							(mid 0.249642 -0.249642)
							(end 0.2794 -0.1778)
						)
						(arc
							(start 0.2794 0.1778)
							(mid 0.249642 0.249642)
							(end 0.1778 0.2794)
						)
					)
					(width 0)
					(fill yes)
				)
			)
		)
	)
	(footprint ""
		(layer "B.Cu")
		(at 1.3462 -148.336 90)
		(property "Reference" "C9L14"
			(at 0 0 90)
			(layer "B.SilkS")
			(hide yes)
			(effects
				(font
					(size 1.27 1.27)
				)
				(justify mirror)
			)
		)
		(property "Value" ""
			(at 0 0 90)
			(layer "B.Fab")
			(effects
				(font
					(size 1.27 1.27)
				)
				(justify mirror)
			)
		)
		(duplicate_pad_numbers_are_jumpers no)
		(fp_rect
			(start -0.7239 -0.2159)
			(end 0.7239 1.9939)
			(stroke
				(width 0)
				(type default)
			)
			(fill no)
			(layer "B.CrtYd")
		)
		(fp_line
			(start 0.7239 -0.2159)
			(end 0.7239 1.9939)
			(stroke
				(width 0.1)
				(type default)
			)
			(layer "B.Fab")
		)
		(fp_line
			(start -0.7239 -0.2159)
			(end 0.7239 -0.2159)
			(stroke
				(width 0.1)
				(type default)
			)
			(layer "B.Fab")
		)
		(fp_line
			(start 0.7239 1.9939)
			(end -0.7239 1.9939)
			(stroke
				(width 0.1)
				(type default)
			)
			(layer "B.Fab")
		)
		(fp_line
			(start -0.7239 1.9939)
			(end -0.7239 -0.2159)
			(stroke
				(width 0.1)
				(type default)
			)
			(layer "B.Fab")
		)
		(pad "1" smd rect
			(at 0 0 270)
			(size 1.27 1.016)
			(layers "B.Cu" "B.Mask" "B.Paste")
			(net "VR_FET_SW_P12V_STBY_PVDDQ_KLM")
		)
		(pad "2" smd rect
			(at 0 1.778 270)
			(size 1.27 1.016)
			(layers "B.Cu" "B.Mask" "B.Paste")
			(net "GND")
		)
		(zone
			(layer "B.Cu")
			(hatch none 0.5)
			(connect_pads
				(clearance 0)
			)
			(min_thickness 0.25)
			(keepout
				(tracks not_allowed)
				(vias allowed)
				(pads allowed)
				(copperpour not_allowed)
				(footprints allowed)
			)
			(placement
				(enabled no)
				(sheetname "")
			)
			(fill
				(thermal_gap 0.5)
				(thermal_bridge_width 0.5)
				(island_removal_mode 0)
			)
			(polygon
				(pts
					(xy 1.8542 -147.701) (xy 2.6162 -147.701) (xy 2.6162 -148.971) (xy 1.8542 -148.971)
				)
			)
		)
	)
	(footprint ""
		(layer "B.Cu")
		(at 458.2414 -130.9624 90)
		(property "Reference" "C1M30"
			(at 0 0 90)
			(layer "B.SilkS")
			(hide yes)
			(effects
				(font
					(size 1.27 1.27)
				)
				(justify mirror)
			)
		)
		(property "Value" ""
			(at 0 0 90)
			(layer "B.Fab")
			(effects
				(font
					(size 1.27 1.27)
				)
				(justify mirror)
			)
		)
		(duplicate_pad_numbers_are_jumpers no)
		(fp_poly
			(pts
				(xy -0.3048 -0.1016) (xy -0.3048 0.9906) (xy 0.3048 0.9906) (xy 0.3048 -0.1016)
			)
			(stroke
				(width 0)
				(type default)
			)
			(fill no)
			(layer "B.CrtYd")
		)
		(fp_line
			(start 0.3048 -0.1016)
			(end 0.3048 0.9906)
			(stroke
				(width 0.1)
				(type default)
			)
			(layer "B.Fab")
		)
		(fp_line
			(start -0.3048 -0.1016)
			(end 0.3048 -0.1016)
			(stroke
				(width 0.1)
				(type default)
			)
			(layer "B.Fab")
		)
		(fp_line
			(start 0.3048 0.9906)
			(end -0.3048 0.9906)
			(stroke
				(width 0.1)
				(type default)
			)
			(layer "B.Fab")
		)
		(fp_line
			(start -0.3048 0.9906)
			(end -0.3048 -0.1016)
			(stroke
				(width 0.1)
				(type default)
			)
			(layer "B.Fab")
		)
		(pad "1" smd rect
			(at 0 0 270)
			(size 0.508 0.508)
			(layers "B.Cu" "B.Mask" "B.Paste")
			(net "P3V3_STBY")
		)
		(pad "2" smd rect
			(at 0 0.889 270)
			(size 0.508 0.508)
			(layers "B.Cu" "B.Mask" "B.Paste")
			(net "GND")
		)
		(zone
			(layer "B.Cu")
			(hatch none 0.5)
			(connect_pads
				(clearance 0)
			)
			(min_thickness 0.25)
			(keepout
				(tracks allowed)
				(vias not_allowed)
				(pads allowed)
				(copperpour not_allowed)
				(footprints allowed)
			)
			(placement
				(enabled no)
				(sheetname "")
			)
			(fill
				(thermal_gap 0.5)
				(thermal_bridge_width 0.5)
				(island_removal_mode 0)
			)
			(polygon
				(pts
					(xy 458.4954 -131.2164) (xy 458.4954 -130.7084) (xy 458.8764 -130.7084) (xy 458.8764 -131.2164)
				)
			)
		)
		(zone
			(layer "B.Cu")
			(hatch none 0.5)
			(connect_pads
				(clearance 0)
			)
			(min_thickness 0.25)
			(keepout
				(tracks not_allowed)
				(vias allowed)
				(pads allowed)
				(copperpour not_allowed)
				(footprints allowed)
			)
			(placement
				(enabled no)
				(sheetname "")
			)
			(fill
				(thermal_gap 0.5)
				(thermal_bridge_width 0.5)
				(island_removal_mode 0)
			)
			(polygon
				(pts
					(xy 458.8764 -131.2164) (xy 458.8764 -130.7084) (xy 458.4954 -130.7084) (xy 458.4954 -131.2164)
				)
			)
		)
	)
	(footprint ""
		(layer "B.Cu")
		(at 481.364798 -28.131008)
		(property "Reference" "R2T21"
			(at 0 0 0)
			(layer "B.SilkS")
			(hide yes)
			(effects
				(font
					(size 1.27 1.27)
				)
				(justify mirror)
			)
		)
		(property "Value" ""
			(at 0 0 0)
			(layer "B.Fab")
			(effects
				(font
					(size 1.27 1.27)
				)
				(justify mirror)
			)
		)
		(duplicate_pad_numbers_are_jumpers no)
		(fp_poly
			(pts
				(xy 0.4953 -0.2032) (xy -0.4953 -0.2032) (xy -0.4953 1.6002) (xy 0.4953 1.6002)
			)
			(stroke
				(width 0)
				(type default)
			)
			(fill no)
			(layer "B.CrtYd")
		)
		(fp_line
			(start -0.4953 -0.2032)
			(end -0.4953 1.6002)
			(stroke
				(width 0.1)
				(type default)
			)
			(layer "B.Fab")
		)
		(fp_line
			(start -0.4953 1.6002)
			(end 0.4953 1.6002)
			(stroke
				(width 0.1)
				(type default)
			)
			(layer "B.Fab")
		)
		(fp_line
			(start 0.4953 -0.2032)
			(end -0.4953 -0.2032)
			(stroke
				(width 0.1)
				(type default)
			)
			(layer "B.Fab")
		)
		(fp_line
			(start 0.4953 1.6002)
			(end 0.4953 -0.2032)
			(stroke
				(width 0.1)
				(type default)
			)
			(layer "B.Fab")
		)
		(pad "1" smd rect
			(at 0 0 180)
			(size 0.762 0.889)
			(layers "B.Cu" "B.Mask" "B.Paste")
			(net "P3V3_STBY_MNG")
		)
		(pad "2" smd rect
			(at 0 1.397 180)
			(size 0.762 0.889)
			(layers "B.Cu" "B.Mask" "B.Paste")
			(net "P3V3_STBY_MNG_CPU")
		)
		(zone
			(layer "B.Cu")
			(hatch none 0.5)
			(connect_pads
				(clearance 0)
			)
			(min_thickness 0.25)
			(keepout
				(tracks allowed)
				(vias not_allowed)
				(pads allowed)
				(copperpour not_allowed)
				(footprints allowed)
			)
			(placement
				(enabled no)
				(sheetname "")
			)
			(fill
				(thermal_gap 0.5)
				(thermal_bridge_width 0.5)
				(island_removal_mode 0)
			)
			(polygon
				(pts
					(xy 480.983798 -27.178508) (xy 480.983798 -27.686508) (xy 481.745798 -27.686508) (xy 481.745798 -27.178508)
				)
			)
		)
		(zone
			(layer "B.Cu")
			(hatch none 0.5)
			(connect_pads
				(clearance 0)
			)
			(min_thickness 0.25)
			(keepout
				(tracks not_allowed)
				(vias allowed)
				(pads allowed)
				(copperpour not_allowed)
				(footprints allowed)
			)
			(placement
				(enabled no)
				(sheetname "")
			)
			(fill
				(thermal_gap 0.5)
				(thermal_bridge_width 0.5)
				(island_removal_mode 0)
			)
			(polygon
				(pts
					(xy 481.745798 -27.178508) (xy 481.745798 -27.686508) (xy 480.983798 -27.686508) (xy 480.983798 -27.178508)
				)
			)
		)
	)
	(footprint ""
		(layer "B.Cu")
		(at 162.7886 -77.978 90)
		(property "Reference" "R7P9"
			(at 0 0 90)
			(layer "B.SilkS")
			(hide yes)
			(effects
				(font
					(size 1.27 1.27)
				)
				(justify mirror)
			)
		)
		(property "Value" ""
			(at 0 0 90)
			(layer "B.Fab")
			(effects
				(font
					(size 1.27 1.27)
				)
				(justify mirror)
			)
		)
		(duplicate_pad_numbers_are_jumpers no)
		(fp_poly
			(pts
				(xy 0.2794 -0.1016) (xy -0.2794 -0.1016) (xy -0.2794 0.9906) (xy 0.2794 0.9906)
			)
			(stroke
				(width 0)
				(type default)
			)
			(fill no)
			(layer "B.CrtYd")
		)
		(fp_line
			(start 0.2794 -0.1016)
			(end 0.2794 0.9906)
			(stroke
				(width 0.1)
				(type default)
			)
			(layer "B.Fab")
		)
		(fp_line
			(start -0.2794 -0.1016)
			(end 0.2794 -0.1016)
			(stroke
				(width 0.1)
				(type default)
			)
			(layer "B.Fab")
		)
		(fp_line
			(start 0.2794 0.9906)
			(end -0.2794 0.9906)
			(stroke
				(width 0.1)
				(type default)
			)
			(layer "B.Fab")
		)
		(fp_line
			(start -0.2794 0.9906)
			(end -0.2794 -0.1016)
			(stroke
				(width 0.1)
				(type default)
			)
			(layer "B.Fab")
		)
		(pad "1" smd rect
			(at 0 0 270)
			(size 0.508 0.508)
			(layers "B.Cu" "B.Mask" "B.Paste")
			(net "CLK_100M_CPU1_RC_REFCLK1_DP")
		)
		(pad "2" smd rect
			(at 0 0.889 270)
			(size 0.508 0.508)
			(layers "B.Cu" "B.Mask" "B.Paste")
			(net "GND")
		)
		(zone
			(layer "B.Cu")
			(hatch none 0.5)
			(connect_pads
				(clearance 0)
			)
			(min_thickness 0.25)
			(keepout
				(tracks allowed)
				(vias not_allowed)
				(pads allowed)
				(copperpour not_allowed)
				(footprints allowed)
			)
			(placement
				(enabled no)
				(sheetname "")
			)
			(fill
				(thermal_gap 0.5)
				(thermal_bridge_width 0.5)
				(island_removal_mode 0)
			)
			(polygon
				(pts
					(xy 163.0426 -78.232) (xy 163.0426 -77.724) (xy 163.4236 -77.724) (xy 163.4236 -78.232)
				)
			)
		)
		(zone
			(layer "B.Cu")
			(hatch none 0.5)
			(connect_pads
				(clearance 0)
			)
			(min_thickness 0.25)
			(keepout
				(tracks not_allowed)
				(vias allowed)
				(pads allowed)
				(copperpour not_allowed)
				(footprints allowed)
			)
			(placement
				(enabled no)
				(sheetname "")
			)
			(fill
				(thermal_gap 0.5)
				(thermal_bridge_width 0.5)
				(island_removal_mode 0)
			)
			(polygon
				(pts
					(xy 163.4236 -78.232) (xy 163.4236 -77.724) (xy 163.0426 -77.724) (xy 163.0426 -78.232)
				)
			)
		)
	)
	(footprint ""
		(layer "B.Cu")
		(at 351.416874 -26.505916 90)
		(property "Reference" "C3T12"
			(at -1.47828 0.78994 180)
			(unlocked yes)
			(layer "B.SilkS")
			(effects
				(font
					(size 0.4064 0.254)
					(thickness 0.1524)
				)
				(justify mirror)
			)
		)
		(property "Value" ""
			(at 0 0 90)
			(layer "B.Fab")
			(effects
				(font
					(size 1.27 1.27)
				)
				(justify mirror)
			)
		)
		(duplicate_pad_numbers_are_jumpers no)
		(fp_poly
			(pts
				(xy 0.7239 -0.2159) (xy -0.7239 -0.2159) (xy -0.7239 1.9939) (xy 0.7239 1.9939)
			)
			(stroke
				(width 0)
				(type default)
			)
			(fill no)
			(layer "B.CrtYd")
		)
		(fp_line
			(start 0.7239 -0.2159)
			(end 0.7239 1.9939)
			(stroke
				(width 0.1)
				(type default)
			)
			(layer "B.Fab")
		)
		(fp_line
			(start -0.7239 -0.2159)
			(end 0.7239 -0.2159)
			(stroke
				(width 0.1)
				(type default)
			)
			(layer "B.Fab")
		)
		(fp_line
			(start 0.7239 1.9939)
			(end -0.7239 1.9939)
			(stroke
				(width 0.1)
				(type default)
			)
			(layer "B.Fab")
		)
		(fp_line
			(start -0.7239 1.9939)
			(end -0.7239 -0.2159)
			(stroke
				(width 0.1)
				(type default)
			)
			(layer "B.Fab")
		)
		(pad "1" smd rect
			(at 0 0 270)
			(size 1.27 1.016)
			(layers "B.Cu" "B.Mask" "B.Paste")
			(net "VR_FET_SW_P12V_STBY_PVPP_ABC")
		)
		(pad "2" smd rect
			(at 0 1.778 270)
			(size 1.27 1.016)
			(layers "B.Cu" "B.Mask" "B.Paste")
			(net "GND")
		)
		(zone
			(layer "B.Cu")
			(hatch none 0.5)
			(connect_pads
				(clearance 0)
			)
			(min_thickness 0.25)
			(keepout
				(tracks not_allowed)
				(vias allowed)
				(pads allowed)
				(copperpour not_allowed)
				(footprints allowed)
			)
			(placement
				(enabled no)
				(sheetname "")
			)
			(fill
				(thermal_gap 0.5)
				(thermal_bridge_width 0.5)
				(island_removal_mode 0)
			)
			(polygon
				(pts
					(xy 351.924874 -27.140916) (xy 351.924874 -25.870916) (xy 352.686874 -25.870916) (xy 352.686874 -27.140916)
				)
			)
		)
	)
)
